# T6G (Grand Teton) — schematic netlist excerpt (pin names and nets, part order shuffled) for the footprints in the layout excerpt that follows; sources: Cadence DE-HDL packaged netlist, KiCad conversion of 04192023_DAF0TMB3IC0_F0TG_MB_C_brd_V02_OCP.brd

R1568  Q_RES  49.9 1% CHIP  pkg 0402LF  page 86 : A = I3C_SPD_DDRAF_CPU0_SCL ; B = I3C_SPD_DDRA_CPU0_SCL
R774  Q_RES  15.4K 1% CHIP  pkg 0402LF  page 105 : A = PD_CHH_CPU1_DIMM_SAA ; B = GND

(kicad_pcb
	(version 20260206)
	(generator "pcbnew")
	(generator_version "10.0")
	(general
		(thickness 1.6)
		(legacy_teardrops no)
	)
	(paper "A4")
	(title_block
		(title "04192023_DAF0TMB3IC0_F0TG_MB_C_brd_V02_OCP.brd")
		(comment 1 "Grand Teton / footprints 5004-5005 of 8354")
	)
	(layers
		(0 "F.Cu" signal "TOP")
		(4 "In1.Cu" signal "GND")
		(6 "In2.Cu" signal "IN1")
		(8 "In3.Cu" signal "GND1")
		(10 "In4.Cu" signal "IN2")
		(12 "In5.Cu" signal "GND2")
		(14 "In6.Cu" signal "IN3")
		(16 "In7.Cu" signal "GND3")
		(18 "In8.Cu" signal "VCC")
		(20 "In9.Cu" signal "VCC1")
		(22 "In10.Cu" signal "GND4")
		(24 "In11.Cu" signal "IN4")
		(26 "In12.Cu" signal "GND5")
		(28 "In13.Cu" signal "IN5")
		(30 "In14.Cu" signal "GND6")
		(32 "In15.Cu" signal "IN6")
		(34 "In16.Cu" signal "GND7")
		(2 "B.Cu" signal "BOTTOM")
		(9 "F.Adhes" user "F.Adhesive")
		(11 "B.Adhes" user "B.Adhesive")
		(13 "F.Paste" user "Package Geometry/Pastemask Top")
		(15 "B.Paste" user "Package Geometry/Pastemask Bottom")
		(5 "F.SilkS" user "Ref Des/Silkscreen Top")
		(7 "B.SilkS" user "Ref Des/Silkscreen Bottom")
		(1 "F.Mask" user "Board Geometry/Soldermask Top")
		(3 "B.Mask" user "Board Geometry/Soldermask Bottom")
		(17 "Dwgs.User" user "User.Drawings")
		(19 "Cmts.User" user "User.Comments")
		(21 "Eco1.User" user "User.Eco1")
		(23 "Eco2.User" user "User.Eco2")
		(25 "Edge.Cuts" user "Board Geometry/Outline")
		(27 "Margin" user)
		(31 "F.CrtYd" user "Package Geometry/Place Bound Top")
		(29 "B.CrtYd" user "Package Geometry/Place Bound Bottom")
		(35 "F.Fab" user "Ref Des/Assembly Top")
		(33 "B.Fab" user "Ref Des/Assembly Bottom")
	)
	(footprint ""
		(layer "B.Cu")
		(at 172.72762 -194.885564 180)
		(property "Reference" "R774"
			(at 0 0 0)
			(layer "B.SilkS")
			(hide yes)
			(effects
				(font
					(size 1.27 1.27)
				)
				(justify mirror)
			)
		)
		(property "Value" ""
			(at 0 0 0)
			(layer "B.Fab")
			(effects
				(font
					(size 1.27 1.27)
				)
				(justify mirror)
			)
		)
		(duplicate_pad_numbers_are_jumpers no)
		(fp_line
			(start 0.7874 0.4064)
			(end 0.7874 -0.4064)
			(stroke
				(width 0.1524)
				(type default)
			)
			(layer "B.SilkS")
		)
		(fp_line
			(start 0.7874 -0.4064)
			(end -0.7874 -0.4064)
			(stroke
				(width 0.1524)
				(type default)
			)
			(layer "B.SilkS")
		)
		(fp_line
			(start -0.7874 0.4064)
			(end 0.7874 0.4064)
			(stroke
				(width 0.1524)
				(type default)
			)
			(layer "B.SilkS")
		)
		(fp_line
			(start -0.7874 -0.4064)
			(end -0.7874 0.4064)
			(stroke
				(width 0.1524)
				(type default)
			)
			(layer "B.SilkS")
		)
		(fp_line
			(start 0.67945 0.3048)
			(end 0.67945 -0.305054)
			(stroke
				(width 0.1)
				(type default)
			)
			(layer "B.Fab")
		)
		(fp_line
			(start 0.67945 -0.305054)
			(end 0.12065 -0.305054)
			(stroke
				(width 0.1)
				(type default)
			)
			(layer "B.Fab")
		)
		(fp_line
			(start 0.12065 0.3048)
			(end 0.67945 0.3048)
			(stroke
				(width 0.1)
				(type default)
			)
			(layer "B.Fab")
		)
		(fp_line
			(start 0.12065 0.2794)
			(end 0.12065 0.3048)
			(stroke
				(width 0.1)
				(type default)
			)
			(layer "B.Fab")
		)
		(fp_line
			(start 0.12065 -0.2794)
			(end -0.12065 -0.2794)
			(stroke
				(width 0.1)
				(type default)
			)
			(layer "B.Fab")
		)
		(fp_line
			(start 0.12065 -0.305054)
			(end 0.12065 -0.2794)
			(stroke
				(width 0.1)
				(type default)
			)
			(layer "B.Fab")
		)
		(fp_line
			(start -0.120396 0.3048)
			(end -0.120396 0.2794)
			(stroke
				(width 0.1)
				(type default)
			)
			(layer "B.Fab")
		)
		(fp_line
			(start -0.120396 0.2794)
			(end 0.12065 0.2794)
			(stroke
				(width 0.1)
				(type default)
			)
			(layer "B.Fab")
		)
		(fp_line
			(start -0.12065 -0.2794)
			(end -0.12065 -0.3048)
			(stroke
				(width 0.1)
				(type default)
			)
			(layer "B.Fab")
		)
		(fp_line
			(start -0.12065 -0.3048)
			(end -0.67945 -0.3048)
			(stroke
				(width 0.1)
				(type default)
			)
			(layer "B.Fab")
		)
		(fp_line
			(start -0.67945 0.3048)
			(end -0.120396 0.3048)
			(stroke
				(width 0.1)
				(type default)
			)
			(layer "B.Fab")
		)
		(fp_line
			(start -0.67945 -0.3048)
			(end -0.67945 0.3048)
			(stroke
				(width 0.1)
				(type default)
			)
			(layer "B.Fab")
		)
		(pad "1" smd circle
			(at 0.40005 0)
			(size 0 0)
			(layers "B.Cu" "B.Mask" "B.Paste")
			(net "PD_CHH_CPU1_DIMM_SAA")
		)
		(pad "2" smd circle
			(at -0.40005 0)
			(size 0 0)
			(layers "B.Cu" "B.Mask" "B.Paste")
			(net "GND")
		)
	)
	(footprint ""
		(layer "B.Cu")
		(at 307.34127 -194.98691 180)
		(property "Reference" "R1568"
			(at 0 0 0)
			(layer "B.SilkS")
			(hide yes)
			(effects
				(font
					(size 1.27 1.27)
				)
				(justify mirror)
			)
		)
		(property "Value" ""
			(at 0 0 0)
			(layer "B.Fab")
			(effects
				(font
					(size 1.27 1.27)
				)
				(justify mirror)
			)
		)
		(duplicate_pad_numbers_are_jumpers no)
		(fp_line
			(start 0.7874 0.4064)
			(end 0.7874 -0.4064)
			(stroke
				(width 0.1524)
				(type default)
			)
			(layer "B.SilkS")
		)
		(fp_line
			(start 0.7874 -0.4064)
			(end -0.7874 -0.4064)
			(stroke
				(width 0.1524)
				(type default)
			)
			(layer "B.SilkS")
		)
		(fp_line
			(start -0.7874 0.4064)
			(end 0.7874 0.4064)
			(stroke
				(width 0.1524)
				(type default)
			)
			(layer "B.SilkS")
		)
		(fp_line
			(start -0.7874 -0.4064)
			(end -0.7874 0.4064)
			(stroke
				(width 0.1524)
				(type default)
			)
			(layer "B.SilkS")
		)
		(fp_line
			(start 0.67945 0.3048)
			(end 0.67945 -0.305054)
			(stroke
				(width 0.1)
				(type default)
			)
			(layer "B.Fab")
		)
		(fp_line
			(start 0.67945 -0.305054)
			(end 0.12065 -0.305054)
			(stroke
				(width 0.1)
				(type default)
			)
			(layer "B.Fab")
		)
		(fp_line
			(start 0.12065 0.3048)
			(end 0.67945 0.3048)
			(stroke
				(width 0.1)
				(type default)
			)
			(layer "B.Fab")
		)
		(fp_line
			(start 0.12065 0.2794)
			(end 0.12065 0.3048)
			(stroke
				(width 0.1)
				(type default)
			)
			(layer "B.Fab")
		)
		(fp_line
			(start 0.12065 -0.2794)
			(end -0.12065 -0.2794)
			(stroke
				(width 0.1)
				(type default)
			)
			(layer "B.Fab")
		)
		(fp_line
			(start 0.12065 -0.305054)
			(end 0.12065 -0.2794)
			(stroke
				(width 0.1)
				(type default)
			)
			(layer "B.Fab")
		)
		(fp_line
			(start -0.120396 0.3048)
			(end -0.120396 0.2794)
			(stroke
				(width 0.1)
				(type default)
			)
			(layer "B.Fab")
		)
		(fp_line
			(start -0.120396 0.2794)
			(end 0.12065 0.2794)
			(stroke
				(width 0.1)
				(type default)
			)
			(layer "B.Fab")
		)
		(fp_line
			(start -0.12065 -0.2794)
			(end -0.12065 -0.3048)
			(stroke
				(width 0.1)
				(type default)
			)
			(layer "B.Fab")
		)
		(fp_line
			(start -0.12065 -0.3048)
			(end -0.67945 -0.3048)
			(stroke
				(width 0.1)
				(type default)
			)
			(layer "B.Fab")
		)
		(fp_line
			(start -0.67945 0.3048)
			(end -0.120396 0.3048)
			(stroke
				(width 0.1)
				(type default)
			)
			(layer "B.Fab")
		)
		(fp_line
			(start -0.67945 -0.3048)
			(end -0.67945 0.3048)
			(stroke
				(width 0.1)
				(type default)
			)
			(layer "B.Fab")
		)
		(pad "1" smd circle
			(at 0.40005 0)
			(size 0 0)
			(layers "B.Cu" "B.Mask" "B.Paste")
			(net "I3C_SPD_DDRAF_CPU0_SCL")
		)
		(pad "2" smd circle
			(at -0.40005 0)
			(size 0 0)
			(layers "B.Cu" "B.Mask" "B.Paste")
			(net "I3C_SPD_DDRA_CPU0_SCL")
		)
	)
)
